FILE_TYPE = CONNECTIVITY;
{Allegro Design Entry HDL 16.6-p007 (v16-6-112F) 10/10/2012}
"PAGE_NUMBER" = 233;
0"NC";
1"PVPP_GHJ\g";
2"GND\g";
3"GND\g";
4"AGND_PVPP_GHJ\g";
5"PVPP_GHJ\g";
6"GND\g";
7"P3V3_STBY\g";
8"GND\g";
9"P12V_STBY\g";
10"GND\g";
11"GND\g";
12"GND\g";
13"GND\g";
14"GND\g";
15"GND\g";
16"GND\g";
17"AGND_PVPP_GHJ\g";
18"AGND_PVPP_GHJ\g";
19"AGND_PVPP_GHJ\g";
20"AGND_PVPP_GHJ\g";
21"AGND_PVPP_GHJ\g";
22"GND\g";
23"AGND_PVPP_GHJ\g";
24"GND\g";
25"GND\g";
26"GND\g";
27"GND\g";
28"GND\g";
29"AGND_PVPP_GHJ\g";
30"GND\g";
31"GND\g";
32"VR_FET_SW_P12V_STBY_PVPP_GHJ";
33"VR_PVPP_GHJ_SS";
34"VR_COMP_RC_PVPP_GHJ";
35"VR_PVPP_GHJ_SNUB";
36"FM_PVPP_CPU1_EN";
37"VR_PVPP_GHJ_BOOT_R";
38"VR_PVPP_GHJ_PHASE";
39"VR_PVPP_GHJ_BOOT";
40"VSENSE_PVPP_GHJ";
41"VR_COMP_PVPP_GHJ";
42"VR_COMP_PVPP_GHJ_3";
43"VR_VB_PVPP_GHJ";
44"VR_FB_PVPP_GHJ";
45"FM_PVPP_PVDDQ_CPU1_EN_GHJ";
46"PWRGD_PVPP_GHJ";
47"VR_PVPP_GHJ_ISET";
48"PWRGD_PVPP_GHJ_R";
%"CAP"
"1","(-8150,725)","0","mstr_discrete","I109";
;
MATERIAL"X6S"
TOLERANCE"20%"
PART_NUMBER"E15431-001"
VALUE"10UF"
LOCATION"C7U4"
PACK_TYPE"0603LF"
VOLTAGE"4V"
GROUP"PWR_MLCC_CAP"
CDS_LIB"mstr_discrete"
BOM_COST"MEM_VRD_PVPP_AB"
CDS_SEC"1"
$SEC"1"
CDS_LOCATION"C7U4"
ROOM"PVPP_KLM_VR";
"A"
$PN"1"1;
"B"
$PN"2"2;
%"PVPP_GHJ"
"1","(-8100,1000)","0","mstr_symbols","I110";
;
ROOM"PVPP_KLM_VR"
BOM_COST"MEM_VRD_PVPP_AB"
CDS_LIB"mstr_symbols"
VOLTAGE"2.5V"
BODY_TYPE"PLUMBING"
HDL_POWER"PVPP_GHJ";
"G\NAC"1;
%"CAP"
"1","(-7875,725)","0","mstr_discrete","I111";
;
TOLERANCE"20%"
PACK_TYPE"0603LF"
VALUE"10UF"
LOCATION"C7U5"
MATERIAL"X6S"
PART_NUMBER"E15431-001"
VOLTAGE"4V"
GROUP"PWR_MLCC_CAP"
BOM_COST"MEM_VRD_PVPP_AB"
CDS_SEC"1"
$SEC"1"
CDS_LOCATION"C7U5"
ROOM"PVPP_KLM_VR"
CDS_LIB"mstr_discrete";
"A"
$PN"1"1;
"B"
$PN"2"2;
%"CAP"
"1","(-7600,725)","0","mstr_discrete","I112";
;
TOLERANCE"20%"
LOCATION"C7T2"
PART_NUMBER"E15431-001"
VALUE"10UF"
MATERIAL"X6S"
VOLTAGE"4V"
PACK_TYPE"0603LF"
GROUP"PWR_MLCC_CAP"
BOM_COST"MEM_VRD_PVPP_AB"
CDS_SEC"1"
$SEC"1"
CDS_LOCATION"C7T2"
ROOM"PVPP_KLM_VR"
CDS_LIB"mstr_discrete";
"A"
$PN"1"1;
"B"
$PN"2"2;
%"CAP"
"1","(-7325,725)","0","mstr_discrete","I113";
;
TOLERANCE"20%"
MATERIAL"X6S"
VALUE"10UF"
LOCATION"C7T3"
VOLTAGE"4V"
PACK_TYPE"0603LF"
PART_NUMBER"E15431-001"
GROUP"PWR_MLCC_CAP"
CDS_LIB"mstr_discrete"
ROOM"PVPP_KLM_VR"
CDS_LOCATION"C7T3"
$SEC"1"
CDS_SEC"1"
BOM_COST"MEM_VRD_PVPP_AB";
"A"
$PN"1"1;
"B"
$PN"2"2;
%"CAP"
"1","(-7050,725)","0","mstr_discrete","I115";
;
VALUE"10UF"
TOLERANCE"20%"
MATERIAL"X6S"
LOCATION"C7U6"
PART_NUMBER"E15431-001"
PACK_TYPE"0603LF"
VOLTAGE"4V"
GROUP"PWR_MLCC_CAP"
BOM_COST"MEM_VRD_PVPP_AB"
CDS_SEC"1"
$SEC"1"
CDS_LOCATION"C7U6"
ROOM"PVPP_KLM_VR"
CDS_LIB"mstr_discrete";
"A"
$PN"1"1;
"B"
$PN"2"2;
%"CAP"
"1","(-6750,725)","0","mstr_discrete","I116";
;
PACK_TYPE"0603LF"
PART_NUMBER"E15431-001"
MATERIAL"X6S"
TOLERANCE"20%"
VALUE"10UF"
LOCATION"C3F3"
VOLTAGE"4V"
GROUP"PWR_MLCC_CAP"
CDS_SEC"1"
$SEC"1"
BOM_COST"MEM_VRD_PVPP_AB"
ROOM"PVPP_KLM_VR"
CDS_LOCATION"C3F3"
CDS_LIB"mstr_discrete";
"A"
$PN"1"1;
"B"
$PN"2"2;
%"CAP"
"1","(-6475,725)","0","mstr_discrete","I117";
;
LOCATION"C3F4"
TOLERANCE"20%"
PART_NUMBER"E15431-001"
VALUE"10UF"
MATERIAL"X6S"
VOLTAGE"4V"
PACK_TYPE"0603LF"
GROUP"PWR_MLCC_CAP"
CDS_SEC"1"
$SEC"1"
BOM_COST"MEM_VRD_PVPP_AB"
ROOM"PVPP_KLM_VR"
CDS_LOCATION"C3F4"
CDS_LIB"mstr_discrete";
"A"
$PN"1"1;
"B"
$PN"2"2;
%"CAP"
"1","(-6175,725)","0","mstr_discrete","I118";
;
TOLERANCE"20%"
PART_NUMBER"E15431-001"
LOCATION"C3G3"
VALUE"10UF"
MATERIAL"X6S"
VOLTAGE"4V"
PACK_TYPE"0603LF"
GROUP"PWR_MLCC_CAP"
BOM_COST"MEM_VRD_PVPP_AB"
CDS_SEC"1"
$SEC"1"
CDS_LOCATION"C3G3"
ROOM"PVPP_KLM_VR"
CDS_LIB"mstr_discrete";
"A"
$PN"1"1;
"B"
$PN"2"2;
%"CAP"
"1","(-5875,725)","0","mstr_discrete","I132";
;
PART_NUMBER"E15431-001"
MATERIAL"X6S"
TOLERANCE"20%"
VOLTAGE"4V"
VALUE"10UF"
LOCATION"C3G7"
PACK_TYPE"0603LF"
GROUP"PWR_MLCC_CAP"
BOM_COST"MEM_VRD_PVPP_AB"
CDS_SEC"1"
$SEC"1"
CDS_LOCATION"C3G7"
ROOM"PVPP_KLM_VR"
CDS_LIB"mstr_discrete";
"A"
$PN"1"1;
"B"
$PN"2"2;
%"CAP"
"1","(-5600,725)","0","mstr_discrete","I133";
;
VALUE"10UF"
LOCATION"C3G4"
VOLTAGE"4V"
PACK_TYPE"0603LF"
PART_NUMBER"E15431-001"
MATERIAL"X6S"
TOLERANCE"20%"
GROUP"PWR_MLCC_CAP"
CDS_LIB"mstr_discrete"
CDS_LOCATION"C3G4"
BOM_COST"MEM_VRD_PVPP_AB"
ROOM"PVPP_KLM_VR"
$SEC"1"
CDS_SEC"1";
"A"
$PN"1"1;
"B"
$PN"2"2;
%"GND"
"1","(-8150,275)","0","mstr_symbols","I134";
;
HDL_POWER"GND"
BODY_TYPE"PLUMBING"
ROOM"PVPP_KLM_VR"
CDS_LIB"mstr_symbols"
VOLTAGE"0"
BOM_COST"MEM_VRD_PVPP_AB"
SIZE"1B";
"A\NAC"2;
%"CAP"
"1","(-5325,725)","0","mstr_discrete","I135";
;
TOLERANCE"20%"
MATERIAL"X6S"
PART_NUMBER"E15431-001"
LOCATION"C3G8"
VOLTAGE"4V"
VALUE"10UF"
PACK_TYPE"0603LF"
GROUP"PWR_MLCC_CAP"
CDS_LIB"mstr_discrete"
BOM_COST"MEM_VRD_PVPP_AB"
CDS_LOCATION"C3G8"
ROOM"PVPP_KLM_VR"
$SEC"1"
CDS_SEC"1";
"A"
$PN"1"1;
"B"
$PN"2"2;
%"CAP"
"1","(-5000,725)","0","mstr_discrete","I136";
;
CDS_SEC"1"
MATERIAL"X6S"
PART_NUMBER"E15431-001"
PACK_TYPE"0603LF"
LOCATION"C7U3"
VALUE"10UF"
GROUP"PWR_MLCC_CAP"
TOLERANCE"20%"
VOLTAGE"4V"
SEC"1"
BOM_COST"MEM_VRD_PVPP_AB"
SEC_TYPE"0603LF"
ROOM"PVPP_KLM_VR"
CDS_LOCATION"C7U3"
CDS_LIB"mstr_discrete";
"A"
$PN"1"1;
"B"
$PN"2"2;
%"GND"
"1","(-1400,450)","0","mstr_symbols","I156";
;
VOLTAGE"0"
SIZE"1B"
CDS_LIB"mstr_symbols"
ROOM"PVPP_KLM_VR"
BOM_COST"PVPP_KLM_VR"
BODY_TYPE"PLUMBING"
HDL_POWER"GND";
"A\NAC"3;
%"RES"
"1","(-1100,550)","0","mstr_discrete","I157";
;
CDS_LOCATION"R4G25"
LOCATION"R4G25"
PART_NUMBER"G21497-005"
MATERIAL"CHIP"
VALUE"0.0"
TOLERANCE"5%"
PACK_TYPE"0402"
WATTAGE"1/16W"
$SEC"1"
CDS_SEC"1"
ROOM"PVPP_KLM_VR"
CDS_LIB"mstr_discrete";
"B"
$PN"2"4;
"A"
$PN"1"3;
%"AGND_SCSI"
"1","(-850,450)","0","mstr_symbols","I158";
;
HDL_POWER"AGND_PVPP_GHJ"
BOM_COST"PVPP_KLM_VR"
ROOM"PVPP_KLM_VR"
VOLTAGE"0.0V"
CDS_LIB"mstr_symbols"
BODY_TYPE"PLUMBING";
"A"4;
%"PVPP_GHJ"
"1","(-725,3825)","0","mstr_symbols","I174";
;
ROOM"PVPP_KLM_VR"
BOM_COST"PVPP_KLM_VR"
CDS_LIB"mstr_symbols"
VOLTAGE"2.5V"
BODY_TYPE"PLUMBING"
HDL_POWER"PVPP_GHJ";
"G\NAC"5;
%"GND"
"1","(-7100,1900)","0","mstr_symbols","I180";
;
SIZE"1B"
CDS_LIB"mstr_symbols"
VOLTAGE"0"
ROOM"PVPP_KLM_VR"
BOM_COST"PVPP_KLM_VR"
BOM"SYSB_CPLD"
BODY_TYPE"PLUMBING"
HDL_POWER"GND";
"A\NAC"6;
%"RES"
"2","(-7100,2200)","0","mstr_discrete","I182";
;
VALUE"10.0K"
TOLERANCE"1%"
WATTAGE"1/16W"
LOCATION"R4G5"
MATERIAL"CHIP"
PART_NUMBER"G21796-016"
PACK_TYPE"0402"
BOM_COST"PVPP_KLM_VR"
BOM"SYSB_CPLD"
CDS_SEC"1"
$SEC"1"
CDS_LOCATION"R4G5"
ROOM"PVPP_KLM_VR"
CDS_LIB"mstr_discrete";
"A"
$PN"1"36;
"B"
$PN"2"6;
%"CAP"
"1","(-6500,2200)","2","mstr_discrete","I183";
;
VOLTAGE"50V"
LOCATION"C4G7"
VALUE"1000PF"
TOLERANCE"10%"
MATERIAL"EMPTY"
PART_NUMBER"A36096-046"
PACK_TYPE"0402LF"
FIN"VR_1P2"
REUSE_ID"1"
CDS_SEC"1"
$SEC"1"
CDS_LOCATION"C4G7"
CDS_LIB"mstr_discrete"
BOM_COST"PVPP_KLM_VR"
ROOM"PVPP_KLM_VR";
"A"
$PN"1"36;
"B"
$PN"2"17;
%"RES"
"2","(-4150,1100)","0","mstr_discrete","I185";
;
CDS_SEC"1"
LOCATION"R4G14"
MATERIAL"CHIP"
WATTAGE"1/16W"
TOLERANCE"1%"
VALUE"1.00K"
PART_NUMBER"G21796-026"
PACK_TYPE"0402"
BOM_COST"PVPP_KLM_VR"
ROOM"PVPP_KLM_VR"
REUSE_ID"21"
SEC_TYPE"0402"
SEC"1"
CDS_LIB"mstr_discrete"
CDS_LOCATION"R4G14";
"A"
$PN"1"7;
"B"
$PN"2"48;
%"P3V3_STBY"
"1","(-4150,1375)","0","mstr_symbols","I186";
;
VOLTAGE"+3.3V"
CDS_LIB"mstr_symbols"
SIZE"1B"
BODY_TYPE"PLUMBING"
HDL_POWER"P3V3_STBY";
"G\NAC"7;
%"CAP"
"1","(-5800,2350)","0","mstr_discrete","I187";
;
CDS_SEC"1"
LOCATION"C6U6"
VOLTAGE"6.3V"
VALUE"4.7UF"
TOLERANCE"10%"
PACK_TYPE"0603"
PART_NUMBER"E15431-003"
MATERIAL"X6S"
CONFIG"078.47521.08BD"
SEC"1"
CDS_LOCATION"C6U6"
ROOM"PVPP_KLM_VR"
BOM_COST"PVPP_KLM_VR"
SEC_TYPE"0603"
REUSE_ID"26"
CDS_LIB"mstr_discrete";
"A"
$PN"1"43;
"B"
$PN"2"18;
%"CAP"
"1","(-5000,2025)","0","mstr_discrete","I194";
;
CDS_SEC"1"
VALUE"0.027UF"
LOCATION"C4G8"
VOLTAGE"16V"
TOLERANCE"10%"
PACK_TYPE"0402"
MATERIAL"X7R"
PART_NUMBER"A36096-129"
ROOM"PVPP_KLM_VR"
CDS_LOCATION"C4G8"
SEC"1"
BOM_COST"PVPP_KLM_VR"
REUSE_ID"26"
SEC_TYPE"0402"
CDS_LIB"mstr_discrete";
"A"
$PN"1"33;
"B"
$PN"2"19;
%"GND"
"1","(-5000,3775)","0","mstr_symbols","I195";
;
SIZE"1B"
CDS_LIB"mstr_symbols"
VOLTAGE"0"
ROOM"PVPP_KLM_VR"
BOM_COST"PVPP_KLM_VR"
BODY_TYPE"PLUMBING"
HDL_POWER"GND";
"A\NAC"8;
%"CAP"
"1","(-5000,4000)","0","mstr_discrete","I196";
;
LOCATION"C4G4"
VOLTAGE"16V"
TOLERANCE"10%"
MATERIAL"X6S"
PACK_TYPE"0402"
VALUE"1.0UF"
PART_NUMBER"D97712-011"
FIN"VR_1P2"
REUSE_ID"1"
CDS_SEC"1"
$SEC"1"
CDS_LOCATION"C4G4"
BOM_COST"PVPP_KLM_VR"
CDS_LIB"mstr_discrete"
ROOM"PVPP_KLM_VR";
"A"
$PN"1"32;
"B"
$PN"2"8;
%"P12V_STBY"
"1","(-7775,4350)","0","mstr_symbols","I197";
;
VOLTAGE"12.0V"
CDS_LIB"mstr_symbols"
SIZE"1B"
BODY_TYPE"PLUMBING"
HDL_POWER"P12V_STBY";
"G\NAC"9;
%"FERRITE"
"1","(-7600,4150)","0","mstr_discrete","I198";
;
CDS_SEC"1"
MATERIAL"FB"
PACK_TYPE"SM"
LOCATION"FB4G1"
VALUE"22"
PART_NUMBER"656554-051"
CDS_LOCATION"FB4G1"
TOLERANCE"1%"
CDS_LIB"mstr_discrete"
ROOM"PVPP_KLM_VR"
SEC_TYPE"SM"
SEC"1";
"A"
$PN"1"9;
"B"
$PN"2"32;
%"GND"
"1","(-3800,325)","0","mstr_symbols","I200";
;
VOLTAGE"0"
CDS_LIB"mstr_symbols"
SIZE"1B"
ROOM"PVPP_KLM_VR"
BOM_COST"PVPP_KLM_VR"
BODY_TYPE"PLUMBING"
HDL_POWER"GND";
"A\NAC"10;
%"CAP"
"1","(-3800,575)","0","mstr_discrete","I201";
;
PART_NUMBER"A36096-046"
PACK_TYPE"0402LF"
VALUE"1000PF"
TOLERANCE"10%"
LOCATION"C4G9"
MATERIAL"X7R"
VOLTAGE"50V"
$SEC"1"
CDS_SEC"1"
REUSE_ID"17"
BOM_COST"PVPP_KLM_VR"
CDS_LIB"mstr_discrete"
CDS_LOCATION"C4G9"
ROOM"PVPP_KLM_VR";
"A"
$PN"1"48;
"B"
$PN"2"10;
%"GND"
"1","(-3000,1775)","0","mstr_symbols","I203";
;
SIZE"1B"
VOLTAGE"0"
CDS_LIB"mstr_symbols"
ROOM"PVPP_KLM_VR"
BOM_COST"PVPP_KLM_VR"
BODY_TYPE"PLUMBING"
HDL_POWER"GND";
"A\NAC"11;
%"GND"
"1","(-2450,2900)","0","mstr_symbols","I207";
;
VOLTAGE"0"
CDS_LIB"mstr_symbols"
SIZE"1B"
ROOM"PVPP_KLM_VR"
BOM_COST"PVPP_KLM_VR"
BODY_TYPE"PLUMBING"
HDL_POWER"GND";
"A\NAC"12;
%"RES"
"2","(-2450,3100)","0","mstr_discrete","I208";
;
LOCATION"R4F6"
MATERIAL"EMPTY"
PACK_TYPE"0402"
TOLERANCE"5%"
VALUE"2.2"
WATTAGE"1/16W"
PART_NUMBER"G21497-016"
REUSE_ID"29"
CDS_SEC"1"
BOM_COST"PVPP_KLM_VR"
$SEC"1"
ROOM"PVPP_KLM_VR"
CDS_LOCATION"R4F6"
CDS_LIB"mstr_discrete";
"A"
$PN"1"35;
"B"
$PN"2"12;
%"CAP"
"1","(-2450,3475)","0","mstr_discrete","I209";
;
VALUE"3300PF"
VOLTAGE"50V"
LOCATION"C4F12"
MATERIAL"EMPTY"
PART_NUMBER"A36096-091"
PACK_TYPE"0402LF"
TOLERANCE"10%"
BOM_COST"PVPP_KLM_VR"
REUSE_ID"26"
CDS_SEC"1"
$SEC"1"
CDS_LOCATION"C4F12"
ROOM"PVPP_KLM_VR"
CDS_LIB"mstr_discrete";
"A"
$PN"1"38;
"B"
$PN"2"35;
%"GND"
"1","(-2000,3325)","0","mstr_symbols","I210";
;
VOLTAGE"0"
SIZE"1B"
CDS_LIB"mstr_symbols"
ROOM"PVPP_KLM_VR"
BOM_COST"PVPP_KLM_VR"
BODY_TYPE"PLUMBING"
HDL_POWER"GND";
"A\NAC"13;
%"RES"
"2","(-2000,3525)","0","mstr_discrete","I211";
;
VALUE"120.0"
TOLERANCE"1%"
LOCATION"R4G6"
WATTAGE"1/10W"
PACK_TYPE"0603"
MATERIAL"CHIP"
PART_NUMBER"G22026-003"
REUSE_ID"34"
CDS_SEC"1"
$SEC"1"
BOM_COST"PVPP_KLM_VR"
ROOM"PVPP_KLM_VR"
CDS_LOCATION"R4G6"
CDS_LIB"mstr_discrete";
"A"
$PN"1"5;
"B"
$PN"2"13;
%"GND"
"1","(-1700,3175)","0","mstr_symbols","I216";
;
BOM_COST"PVPP_KLM_VR"
ROOM"PVPP_KLM_VR"
SIZE"1B"
CDS_LIB"mstr_symbols"
VOLTAGE"0"
BODY_TYPE"PLUMBING"
HDL_POWER"GND";
"A\NAC"14;
%"CAPP"
"1","(-1700,3500)","0","mstr_discrete","I217";
;
LOCATION"C4F7"
VALUE"330UF"
TOLERANCE"20%"
VOLTAGE"6.3V"
MATERIAL"POSCAP"
PACK_TYPE"7343LF"
PART_NUMBER"724613-042"
GROUP"PWR_BULK_CAP"
ROOM"PVPP_KLM_VR"
CDS_LIB"mstr_discrete"
BOM_COST"PVPP_KLM_VR"
REUSE_ID"28"
CDS_SEC"1"
$SEC"1"
CDS_LOCATION"C4F7";
"B"
$PN"2"14;
"A"
$PN"1"5;
%"GND"
"1","(-1075,3325)","0","mstr_symbols","I220";
;
SIZE"1B"
VOLTAGE"0"
CDS_LIB"mstr_symbols"
ROOM"PVPP_KLM_VR"
BOM_COST"PVPP_KLM_VR"
BODY_TYPE"PLUMBING"
HDL_POWER"GND";
"A\NAC"15;
%"CAP"
"1","(-1075,3525)","0","mstr_discrete","I221";
;
MATERIAL"X6S"
TOLERANCE"20%"
VOLTAGE"4V"
VALUE"47UF"
LOCATION"C6U3"
PART_NUMBER"C95333-006"
PACK_TYPE"0805"
GROUP"PWR_MLCC_CAP"
CDS_LOCATION"C6U3"
$SEC"1"
CDS_SEC"1"
REUSE_ID"33"
ROOM"PVPP_KLM_VR"
CDS_LIB"mstr_discrete"
BOM_COST"PVPP_KLM_VR";
"A"
$PN"1"5;
"B"
$PN"2"15;
%"GND"
"1","(-775,3325)","0","mstr_symbols","I222";
;
BOM_COST"PVPP_KLM_VR"
ROOM"PVPP_KLM_VR"
CDS_LIB"mstr_symbols"
VOLTAGE"0"
SIZE"1B"
BODY_TYPE"PLUMBING"
HDL_POWER"GND";
"A\NAC"16;
%"CAP"
"1","(-775,3525)","0","mstr_discrete","I223";
;
MATERIAL"X6S"
VOLTAGE"4V"
VALUE"47UF"
PACK_TYPE"0805"
LOCATION"C6U2"
PART_NUMBER"C95333-006"
GROUP"PWR_MLCC_CAP"
TOLERANCE"20%"
BOM_COST"PVPP_KLM_VR"
CDS_LIB"mstr_discrete"
ROOM"PVPP_KLM_VR"
CDS_LOCATION"C6U2"
$SEC"1"
CDS_SEC"1"
REUSE_ID"33";
"A"
$PN"1"5;
"B"
$PN"2"16;
%"CAP"
"2","(-3300,4050)","2","mstr_discrete","I224";
;
CDS_LOCATION"C4G26"
LOCATION"C4G26"
PART_NUMBER"602433-020"
TOLERANCE"10%"
VALUE"0.1UF"
MATERIAL"X7R"
VOLTAGE"25V"
PACK_TYPE"0603LF"
REUSE_ID"27"
SPOF"TRUE"
BOM_COST"PVPP_KLM_VR"
CDS_SEC"1"
$SEC"1"
ROOM"PVPP_KLM_VR"
CDS_LIB"mstr_discrete";
"A"
$PN"1"38;
"B"
$PN"2"37;
%"NCP3232L"
"1","(-3725,2725)","0","mstr_vreg","I225";
;
CDS_SEC"1"
LOCATION"EU4G1"
PART_NUMBER"H86355-001"
MATERIAL"IC"
CDS_LIB"mstr_vreg"
CDS_LMAN_SYM_OUTLINE"-450,850,450,-900"
PACK_TYPE"SM"
SEC_TYPE"SM"
SEC"1"
CDS_LOCATION"EU4G1";
"PG"
$PN"7"48;
"PGND<0>"
$PN"16"11;
"PGND<1>"
$PN"17"11;
"PGND<2>"
$PN"18"11;
"PGND<3>"
$PN"19"11;
"PGND<4>"
$PN"20"11;
"PGND<5>"
$PN"21"11;
"PGND<6>"
$PN"22"11;
"PGND<8>"
$PN"24"11;
"PGND<7>"
$PN"23"11;
"PGND<9>"
$PN"25"11;
"PGND<10>"
$PN"26"11;
"PGND<11>"
$PN"27"11;
"PGND<12>"
$PN"28"11;
"PGND<13>"
$PN"37"11;
"GND"
$PN"41"11;
"AGND"
$PN"5"21;
"EN"
$PN"40"45;
"SS"
$PN"1"33;
"ISET"
$PN"4"47;
"OTS"
$PN"6"23;
"VIN<6>"
$PN"14"32;
"VIN<7>"
$PN"42"32;
"VCC"
$PN"39"32;
"VIN<1>"
$PN"9"32;
"VIN<5>"
$PN"13"32;
"VIN<4>"
$PN"12"32;
"VIN<3>"
$PN"11"32;
"VIN<2>"
$PN"10"32;
"VIN<0>"
$PN"8"32;
"VB"
$PN"38"43;
"COMP"
$PN"3"42;
"FB"
$PN"2"44;
"VSWH<1>"
$PN"29"38;
"VSWH<0>"
$PN"15"38;
"VSW"
$PN"35"38;
"VSWH<2>"
$PN"30"38;
"VSWH<3>"
$PN"31"38;
"VSWH<4>"
$PN"32"38;
"VSWH<5>"
$PN"33"38;
"VSWH<6>"
$PN"34"38;
"BST"
$PN"36"39;
"VSWH<7>"
$PN"43"38;
%"AGND_SCSI"
"1","(-6500,1900)","0","mstr_symbols","I226";
;
HDL_POWER"AGND_PVPP_GHJ"
VOLTAGE"0.0V"
BOM_COST"PVPP_KLM_VR"
CDS_LIB"mstr_symbols"
ROOM"PVPP_KLM_VR"
BODY_TYPE"PLUMBING";
"A"17;
%"AGND_SCSI"
"1","(-5800,2050)","0","mstr_symbols","I227";
;
HDL_POWER"AGND_PVPP_GHJ"
CDS_LIB"mstr_symbols"
VOLTAGE"0.0V"
ROOM"PVPP_KLM_VR"
BOM_COST"PVPP_KLM_VR"
BODY_TYPE"PLUMBING";
"A"18;
%"AGND_SCSI"
"1","(-5000,1800)","0","mstr_symbols","I228";
;
HDL_POWER"AGND_PVPP_GHJ"
CDS_LIB"mstr_symbols"
VOLTAGE"0.0V"
ROOM"PVPP_KLM_VR"
BOM_COST"PVPP_KLM_VR"
BODY_TYPE"PLUMBING";
"A"19;
%"AGND_SCSI"
"1","(-4675,1250)","0","mstr_symbols","I229";
;
HDL_POWER"AGND_PVPP_GHJ"
VOLTAGE"0"
CDS_LIB"mstr_symbols"
BODY_TYPE"PLUMBING";
"A"20;
%"AGND_SCSI"
"1","(-4300,1700)","0","mstr_symbols","I230";
;
HDL_POWER"AGND_PVPP_GHJ"
VOLTAGE"0.0V"
CDS_LIB"mstr_symbols"
ROOM"PVPP_KLM_VR"
BOM_COST"PVPP_KLM_VR"
BODY_TYPE"PLUMBING";
"A"21;
%"CAP_A"
"1","(-5050,3325)","0","dev_discrete","I242";
;
VALUE"0.1UF"
PACK_TYPE"0402V"
LOCATION"C6U5"
MATERIAL"X7R"
VOLTAGE"16V"
PART_NUMBER"A36096-030"
TOLERANCE"10%"
CDS_LOCATION"C6U5"
CDS_SEC"1"
SEC_TYPE"0402V"
SEC"1"
CDS_LIB"dev_discrete";
"B"
$PN"2"22;
"A"
$PN"1"32;
%"GND"
"1","(-5050,3100)","0","mstr_symbols","I243";
;
VOLTAGE"0"
CDS_LIB"mstr_symbols"
SIZE"1B"
ROOM"PVPP_KLM_VR"
BOM_COST"PVPP_KLM_VR"
BODY_TYPE"PLUMBING"
HDL_POWER"GND";
"A\NAC"22;
%"AGND_SCSI"
"1","(-5300,2575)","0","mstr_symbols","I244";
;
HDL_POWER"AGND_PVPP_GHJ"
CDS_LIB"mstr_symbols"
BOM_COST"PVPP_KLM_VR"
ROOM"PVPP_KLM_VR"
VOLTAGE"0.0V"
BODY_TYPE"PLUMBING";
"A"23;
%"GND"
"1","(-1400,3175)","0","mstr_symbols","I246";
;
HDL_POWER"GND"
BODY_TYPE"PLUMBING"
BOM_COST"PVPP_KLM_VR"
ROOM"PVPP_KLM_VR"
SIZE"1B"
CDS_LIB"mstr_symbols"
VOLTAGE"0";
"A\NAC"24;
%"RES"
"1","(-3375,825)","0","mstr_discrete","I247";
;
CDS_SEC"1"
PACK_TYPE"0402"
PART_NUMBER"G21796-250"
TOLERANCE"1.0%"
MATERIAL"CHIP"
WATTAGE"1/16W"
VALUE"22.1"
LOCATION"R4G12"
SEC_TYPE"0402"
SEC"1"
ROOM"PVPP_GHJ_VR"
CDS_LOCATION"R4G12"
CDS_LIB"mstr_discrete";
"B"
$PN"2"46;
"A"
$PN"1"48;
%"CAP"
"1","(-6600,4000)","0","mstr_discrete","I248";
;
CDS_SEC"1"
LOCATION"C6U4"
PACK_TYPE"0805"
VALUE"10UF"
PART_NUMBER"C95333-007"
MATERIAL"X6S"
VOLTAGE"16V"
TOLERANCE"10%"
CDS_LIB"mstr_discrete"
CDS_LOCATION"C6U4"
SEC"1"
SEC_TYPE"0805";
"A"
$PN"1"32;
"B"
$PN"2"25;
%"GND"
"1","(-6600,3800)","0","mstr_symbols","I249";
;
ROOM"PVPP_KLM_VR"
BOM_COST"PVPP_KLM_VR"
CDS_LIB"mstr_symbols"
VOLTAGE"0"
SIZE"1B"
BODY_TYPE"PLUMBING"
HDL_POWER"GND";
"A\NAC"25;
%"GND"
"1","(-6250,3800)","0","mstr_symbols","I250";
;
BOM_COST"PVPP_KLM_VR"
ROOM"PVPP_KLM_VR"
CDS_LIB"mstr_symbols"
SIZE"1B"
VOLTAGE"0"
BODY_TYPE"PLUMBING"
HDL_POWER"GND";
"A\NAC"26;
%"GND"
"1","(-5875,3800)","0","mstr_symbols","I251";
;
VOLTAGE"0"
SIZE"1B"
CDS_LIB"mstr_symbols"
ROOM"PVPP_KLM_VR"
BOM_COST"PVPP_KLM_VR"
BODY_TYPE"PLUMBING"
HDL_POWER"GND";
"A\NAC"27;
%"GND"
"1","(-5450,3800)","0","mstr_symbols","I252";
;
SIZE"1B"
VOLTAGE"0"
CDS_LIB"mstr_symbols"
ROOM"PVPP_KLM_VR"
BOM_COST"PVPP_KLM_VR"
BODY_TYPE"PLUMBING"
HDL_POWER"GND";
"A\NAC"28;
%"CAP"
"1","(-6250,4000)","0","mstr_discrete","I253";
;
CDS_SEC"1"
LOCATION"C4G2"
VALUE"10UF"
PACK_TYPE"0805"
MATERIAL"X6S"
VOLTAGE"16V"
TOLERANCE"10%"
PART_NUMBER"C95333-007"
SEC_TYPE"0805"
SEC"1"
CDS_LOCATION"C4G2"
CDS_LIB"mstr_discrete";
"A"
$PN"1"32;
"B"
$PN"2"26;
%"CAP"
"1","(-5875,4000)","0","mstr_discrete","I254";
;
CDS_SEC"1"
MATERIAL"X6S"
TOLERANCE"10%"
VOLTAGE"16V"
VALUE"10UF"
LOCATION"C6U7"
PART_NUMBER"C95333-007"
PACK_TYPE"0805"
SEC_TYPE"0805"
SEC"1"
CDS_LOCATION"C6U7"
CDS_LIB"mstr_discrete";
"A"
$PN"1"32;
"B"
$PN"2"27;
%"CAP"
"1","(-5450,4000)","0","mstr_discrete","I255";
;
CDS_SEC"1"
LOCATION"C6U8"
VALUE"10UF"
VOLTAGE"16V"
TOLERANCE"10%"
MATERIAL"X6S"
PACK_TYPE"0805"
PART_NUMBER"C95333-007"
SEC_TYPE"0805"
SEC"1"
CDS_LOCATION"C6U8"
CDS_LIB"mstr_discrete";
"A"
$PN"1"32;
"B"
$PN"2"28;
%"CAPP"
"1","(-1400,3500)","0","mstr_discrete","I256";
;
CDS_SEC"1"
PART_NUMBER"724613-067"
PACK_TYPE"7343"
MATERIAL"POSCAP"
VOLTAGE"4V"
TOLERANCE"20%"
VALUE"220UF"
LOCATION"C4F11"
GROUP"PWR_BULK_CAP"
CDS_LOCATION"C4F11"
SEC"1"
SEC_TYPE"7343"
CDS_LIB"mstr_discrete";
"B"
$PN"2"24;
"A"
$PN"1"5;
%"RES"
"2","(-950,2475)","0","mstr_discrete","I266";
;
CDS_SEC"1"
LOCATION"R4G10"
VALUE"1.0K"
TOLERANCE"0.1%"
WATTAGE"1/16W"
PACK_TYPE"0402"
MATERIAL"CHIP"
PART_NUMBER"G85996-004"
ROOM"PVPP_KLM_VR"
CDS_LOCATION"R4G10"
SEC"1"
BOM_COST"PVPP_KLM_VR"
REUSE_ID"9"
SEC_TYPE"0402"
SPOF"TRUE"
CDS_LIB"mstr_discrete";
"A"
$PN"1"40;
"B"
$PN"2"41;
%"CAP"
"1","(-950,1700)","0","mstr_discrete","I267";
;
CDS_SEC"1"
PART_NUMBER"A36096-075"
PACK_TYPE"0402LF"
LOCATION"C4G11"
VALUE"2200PF"
TOLERANCE"10%"
MATERIAL"X7R"
VOLTAGE"50V"
CDS_LIB"mstr_discrete"
CDS_LOCATION"C4G11"
ROOM"PVPP_KLM_VR"
BOM_COST"PVPP_KLM_VR"
SEC"1"
SEC_TYPE"0402LF"
SPOF"TRUE"
REUSE_ID"26";
"A"
$PN"1"41;
"B"
$PN"2"44;
%"RES"
"2","(-1275,1800)","0","mstr_discrete","I270";
;
TOLERANCE"1%"
WATTAGE"1/16W"
LOCATION"R4G7"
VALUE"20.0K"
PACK_TYPE"0402"
MATERIAL"CHIP"
PART_NUMBER"G21796-040"
CDS_LIB"mstr_discrete"
BOM_COST"PVPP_KLM_VR"
REUSE_ID"9"
SPOF"TRUE"
CDS_SEC"1"
$SEC"1"
CDS_LOCATION"R4G7"
ROOM"PVPP_KLM_VR";
"A"
$PN"1"40;
"B"
$PN"2"44;
%"RES"
"1","(-1275,2900)","5","mstr_discrete","I271";
;
CDS_SEC"1"
VALUE"0.0"
LOCATION"R4G8"
WATTAGE"1/16W"
TOLERANCE"5%"
MATERIAL"CHIP"
PACK_TYPE"0402"
PART_NUMBER"G21497-005"
CDS_LOCATION"R4G8"
CDS_LIB"mstr_discrete"
SEC_TYPE"0402"
SPOF"TRUE"
ROOM"PVPP_KLM_VR"
SEC"1";
"B"
$PN"2"40;
"A"
$PN"1"5;
%"RES"
"1","(-2000,2300)","0","mstr_discrete","I272";
;
CDS_SEC"1"
LOCATION"R4G13"
PACK_TYPE"0402"
MATERIAL"CHIP"
PART_NUMBER"G21796-242"
TOLERANCE"1.0%"
WATTAGE"1/16W"
VALUE"7.87K"
ROOM"PVPP_KLM_VR"
CDS_LIB"mstr_discrete"
BOM_COST"PVPP_KLM_VR"
SEC"1"
CDS_LOCATION"R4G13"
REUSE_ID"13"
SEC_TYPE"0402";
"B"
$PN"2"44;
"A"
$PN"1"34;
%"CAP"
"2","(-2150,2675)","2","mstr_discrete","I273";
;
CDS_SEC"1"
LOCATION"C4G6"
VOLTAGE"50V"
TOLERANCE"5%"
MATERIAL"COG"
VALUE"100.0PF"
PART_NUMBER"A36095-026"
PACK_TYPE"0402LF"
SEC_TYPE"0402LF"
REUSE_ID"27"
BOM_COST"PVPP_KLM_VR"
SEC"1"
ROOM"PVPP_KLM_VR"
CDS_LOCATION"C4G6"
CDS_LIB"mstr_discrete";
"A"
$PN"1"44;
"B"
$PN"2"42;
%"CAP"
"2","(-2775,2300)","2","mstr_discrete","I274";
;
CDS_SEC"1"
TOLERANCE"10%"
LOCATION"C4G10"
PART_NUMBER"A36096-075"
VALUE"2200PF"
VOLTAGE"50V"
PACK_TYPE"0402LF"
MATERIAL"X7R"
SEC_TYPE"0402LF"
REUSE_ID"27"
SEC"1"
CDS_LIB"mstr_discrete"
CDS_LOCATION"C4G10"
ROOM"PVPP_KLM_VR"
BOM_COST"PVPP_KLM_VR";
"A"
$PN"1"34;
"B"
$PN"2"42;
%"RES"
"1","(-6075,2675)","0","mstr_discrete","I275";
;
CDS_SEC"1"
LOCATION"R4G4"
VALUE"0.0"
MATERIAL"CHIP"
PACK_TYPE"0402"
WATTAGE"1/16W"
TOLERANCE"5%"
PART_NUMBER"G21497-005"
SEC"1"
SEC_TYPE"0402"
ROOM"PVCCIN_CPU0_VR"
CDS_LIB"mstr_discrete"
CDS_LOCATION"R4G4";
"B"
$PN"2"45;
"A"
$PN"1"36;
%"AGND_SCSI"
"1","(-1275,900)","0","mstr_symbols","I276";
;
HDL_POWER"AGND_PVPP_GHJ"
VOLTAGE"0.0V"
BOM_COST"PVPP_KLM_VR"
ROOM"PVPP_KLM_VR"
CDS_LIB"mstr_symbols"
BODY_TYPE"PLUMBING";
"A"29;
%"INDUCTOR"
"1","(-2175,3700)","0","mstr_discrete","I277";
;
CDS_SEC"1"
MATERIAL"IND"
VALUE"0.47UH"
PACK_TYPE"SM"
PART_NUMBER"E13358-018"
LOCATION"L4G1"
TOLERANCE"1%"
SEC_TYPE"SM"
REUSE_ID"30"
SEC"1"
BOM_COST"PVPP_GHJ_VR"
CDS_LIB"mstr_discrete"
ROOM"PVPP_GHJ_VR"
CDS_LOCATION"L4G1";
"INA\NAC"
$PN"1"38;
"INB\NAC"
$PN"2"5;
%"SC22U16V5MX-4-GP"
"1","(-7000,3950)","0","w_hdl","I278";
;
CDS_SEC"1"
CDS_LOCATION"C22W6"
ATTRIBUTE"22UF"
TOLERANCE"20%"
RATED"16V"
TYPE"X6S"
PACK_SIZE"0805"
VALUE"SC22U16V5MX-4-GP"
LOCATION"C22W6"
PACK_TYPE"SMD-BCG5"
SEC"1"
SEC_TYPE"SMD-BCG5"
PART_NUMBER"078.22611.0811"
CDS_LIB"w_hdl"
CDS_LMAN_SYM_OUTLINE"-50,25,50,-25";
"2"
$PN"2"30;
"1"
$PN"1"32;
%"GND"
"1","(-7000,3725)","0","mstr_symbols","I279";
;
CDS_LIB"mstr_symbols"
BOM_COST"PVPP_KLM_VR"
ROOM"PVPP_KLM_VR"
VOLTAGE"0"
SIZE"1B"
BODY_TYPE"PLUMBING"
HDL_POWER"GND";
"A\NAC"30;
%"SC22U16V5MX-4-GP"
"1","(-7300,3950)","0","w_hdl","I280";
;
CDS_SEC"1"
CDS_LOCATION"C4G5"
VALUE"SC22U16V5MX-4-GP"
LOCATION"C4G5"
PACK_SIZE"0805"
TYPE"X6S"
RATED"16V"
TOLERANCE"20%"
ATTRIBUTE"22UF"
PACK_TYPE"SMD-BCG5"
SEC"1"
SEC_TYPE"SMD-BCG5"
PART_NUMBER"078.22611.0811"
CDS_LIB"w_hdl"
CDS_LMAN_SYM_OUTLINE"-50,25,50,-25";
"2"
$PN"2"31;
"1"
$PN"1"32;
%"GND"
"1","(-7300,3725)","0","mstr_symbols","I281";
;
SIZE"1B"
VOLTAGE"0"
ROOM"PVPP_KLM_VR"
BOM_COST"PVPP_KLM_VR"
CDS_LIB"mstr_symbols"
BODY_TYPE"PLUMBING"
HDL_POWER"GND";
"A\NAC"31;
%"RES"
"1","(-4075,4050)","0","mstr_discrete","I282";
;
PART_NUMBER"G22178-002"
VALUE"0"
TOLERANCE"5.0%"
PACK_TYPE"0603"
WATTAGE"1/10W"
LOCATION"R4G24"
CDS_LOCATION"R4G24"
MATERIAL"CHIP"
ROOM"NIC_SPRV"
BOM_COST"NT_GBE_BASE"
CDS_LIB"mstr_discrete"
SEC_TYPE"0603"
SEC"1"
CDS_SEC"1";
"B"
$PN"2"37;
"A"
$PN"1"39;
%"RES"
"2","(-1275,1225)","0","mstr_discrete","I283";
;
PART_NUMBER"G21796-161"
PACK_TYPE"0402"
MATERIAL"CHIP"
WATTAGE"1/16W"
TOLERANCE"1%"
VALUE"6.19K"
LOCATION"R4G9"
CDS_LOCATION"R4G9"
BOM_COST"IO_SLOT"
SEC"1"
SEC_TYPE"0402"
ROOM"IO_SLOT"
CDS_LIB"mstr_discrete"
CDS_SEC"1";
"A"
$PN"1"44;
"B"
$PN"2"29;
%"RES"
"2","(-4675,1500)","2","mstr_discrete","I284";
;
LOCATION"R4G11"
NEW_VALUE"3.9K"
TOLERANCE"1.0%"
WATTAGE"1/16W"
CONFIG"64.39015.6DL"
PACK_TYPE"0402"
MATERIAL"CHIP"
CDS_SEC"1"
$SEC"1"
CDS_LIB"mstr_discrete"
BOM_COST"PVPP_KLM_VR"
ROOM"PVPP_KLM_VR"
VALUE"7.87K"
PART_NUMBER"G21796-242"
CDS_LOCATION"R4G11";
"A"
$PN"1"47;
"B"
$PN"2"20;
END.
